# SCM (Grand Teton) — schematic netlist excerpt (pin names and nets, part order shuffled) for the footprints in the layout excerpt that follows; sources: Cadence DE-HDL packaged netlist, KiCad conversion of 12092022_DA0F0TMDCD0_F0T_Management_Board_D_brd_V3_OCP.brd

R780  Q_RES  0 5% EMPTY  pkg 0402LF  page 17 : A = P2V5_AUX ; B = ADCVREFEXT0
R435  Q_RES  33.2 1% CHIP  pkg 0402LF  page 34 : A = SGPIO_PLD_DO_0 ; B = SGPIO_DO_0

(kicad_pcb
	(version 20260206)
	(generator "pcbnew")
	(generator_version "10.0")
	(general
		(thickness 1.6)
		(legacy_teardrops no)
	)
	(paper "A4")
	(title_block
		(title "12092022_DA0F0TMDCD0_F0T_Management_Board_D_brd_V3_OCP.brd")
		(comment 1 "Grand Teton / footprints 1125-1126 of 1440")
	)
	(layers
		(0 "F.Cu" signal "TOP")
		(4 "In1.Cu" signal "GND")
		(6 "In2.Cu" signal "IN1")
		(8 "In3.Cu" signal "GND1")
		(10 "In4.Cu" signal "IN2")
		(12 "In5.Cu" signal "VCC")
		(14 "In6.Cu" signal "VCC1")
		(16 "In7.Cu" signal "IN3")
		(18 "In8.Cu" signal "GND2")
		(20 "In9.Cu" signal "IN4")
		(22 "In10.Cu" signal "GND3")
		(2 "B.Cu" signal "BOTTOM")
		(9 "F.Adhes" user "F.Adhesive")
		(11 "B.Adhes" user "B.Adhesive")
		(13 "F.Paste" user "Package Geometry/Pastemask Top")
		(15 "B.Paste" user "Package Geometry/Pastemask Bottom")
		(5 "F.SilkS" user "Ref Des/Silkscreen Top")
		(7 "B.SilkS" user "Ref Des/Silkscreen Bottom")
		(1 "F.Mask" user "Board Geometry/Soldermask Top")
		(3 "B.Mask" user "Board Geometry/Soldermask Bottom")
		(17 "Dwgs.User" user "User.Drawings")
		(19 "Cmts.User" user "User.Comments")
		(21 "Eco1.User" user "User.Eco1")
		(23 "Eco2.User" user "User.Eco2")
		(25 "Edge.Cuts" user "Board Geometry/Outline")
		(27 "Margin" user)
		(31 "F.CrtYd" user "Package Geometry/Place Bound Top")
		(29 "B.CrtYd" user "Package Geometry/Place Bound Bottom")
		(35 "F.Fab" user "Ref Des/Assembly Top")
		(33 "B.Fab" user "Ref Des/Assembly Bottom")
	)
	(footprint ""
		(layer "B.Cu")
		(at 15.24 -83.693 90)
		(property "Reference" "R435"
			(at 0 0 90)
			(layer "B.SilkS")
			(hide yes)
			(effects
				(font
					(size 1.27 1.27)
				)
				(justify mirror)
			)
		)
		(property "Value" ""
			(at 0 0 90)
			(layer "B.Fab")
			(effects
				(font
					(size 1.27 1.27)
				)
				(justify mirror)
			)
		)
		(duplicate_pad_numbers_are_jumpers no)
		(fp_line
			(start 0.7874 -0.4064)
			(end -0.7874 -0.4064)
			(stroke
				(width 0.1524)
				(type default)
			)
			(layer "B.SilkS")
		)
		(fp_line
			(start -0.7874 -0.4064)
			(end -0.7874 0.4064)
			(stroke
				(width 0.1524)
				(type default)
			)
			(layer "B.SilkS")
		)
		(fp_line
			(start 0.7874 0.4064)
			(end 0.7874 -0.4064)
			(stroke
				(width 0.1524)
				(type default)
			)
			(layer "B.SilkS")
		)
		(fp_line
			(start -0.7874 0.4064)
			(end 0.7874 0.4064)
			(stroke
				(width 0.1524)
				(type default)
			)
			(layer "B.SilkS")
		)
		(fp_line
			(start 0.67945 -0.305054)
			(end 0.12065 -0.305054)
			(stroke
				(width 0.1)
				(type default)
			)
			(layer "B.Fab")
		)
		(fp_line
			(start 0.12065 -0.305054)
			(end 0.12065 -0.2794)
			(stroke
				(width 0.1)
				(type default)
			)
			(layer "B.Fab")
		)
		(fp_line
			(start -0.12065 -0.3048)
			(end -0.67945 -0.3048)
			(stroke
				(width 0.1)
				(type default)
			)
			(layer "B.Fab")
		)
		(fp_line
			(start -0.67945 -0.3048)
			(end -0.67945 0.3048)
			(stroke
				(width 0.1)
				(type default)
			)
			(layer "B.Fab")
		)
		(fp_line
			(start 0.12065 -0.2794)
			(end -0.12065 -0.2794)
			(stroke
				(width 0.1)
				(type default)
			)
			(layer "B.Fab")
		)
		(fp_line
			(start -0.12065 -0.2794)
			(end -0.12065 -0.3048)
			(stroke
				(width 0.1)
				(type default)
			)
			(layer "B.Fab")
		)
		(fp_line
			(start 0.12065 0.2794)
			(end 0.12065 0.3048)
			(stroke
				(width 0.1)
				(type default)
			)
			(layer "B.Fab")
		)
		(fp_line
			(start -0.120396 0.2794)
			(end 0.12065 0.2794)
			(stroke
				(width 0.1)
				(type default)
			)
			(layer "B.Fab")
		)
		(fp_line
			(start 0.67945 0.3048)
			(end 0.67945 -0.305054)
			(stroke
				(width 0.1)
				(type default)
			)
			(layer "B.Fab")
		)
		(fp_line
			(start 0.12065 0.3048)
			(end 0.67945 0.3048)
			(stroke
				(width 0.1)
				(type default)
			)
			(layer "B.Fab")
		)
		(fp_line
			(start -0.120396 0.3048)
			(end -0.120396 0.2794)
			(stroke
				(width 0.1)
				(type default)
			)
			(layer "B.Fab")
		)
		(fp_line
			(start -0.67945 0.3048)
			(end -0.120396 0.3048)
			(stroke
				(width 0.1)
				(type default)
			)
			(layer "B.Fab")
		)
		(pad "1" smd circle
			(at 0.40005 0 270)
			(size 0 0)
			(layers "B.Cu" "B.Mask" "B.Paste")
			(net "SGPIO_PLD_DO_0")
		)
		(pad "2" smd circle
			(at -0.40005 0 270)
			(size 0 0)
			(layers "B.Cu" "B.Mask" "B.Paste")
			(net "SGPIO_DO_0")
		)
	)
	(footprint ""
		(layer "B.Cu")
		(at 55.336948 -70.418198 90)
		(property "Reference" "R780"
			(at 0 0 90)
			(layer "B.SilkS")
			(hide yes)
			(effects
				(font
					(size 1.27 1.27)
				)
				(justify mirror)
			)
		)
		(property "Value" ""
			(at 0 0 90)
			(layer "B.Fab")
			(effects
				(font
					(size 1.27 1.27)
				)
				(justify mirror)
			)
		)
		(duplicate_pad_numbers_are_jumpers no)
		(fp_line
			(start 0.7874 -0.4064)
			(end -0.7874 -0.4064)
			(stroke
				(width 0.1524)
				(type default)
			)
			(layer "B.SilkS")
		)
		(fp_line
			(start -0.7874 -0.4064)
			(end -0.7874 0.4064)
			(stroke
				(width 0.1524)
				(type default)
			)
			(layer "B.SilkS")
		)
		(fp_line
			(start 0.7874 0.4064)
			(end 0.7874 -0.4064)
			(stroke
				(width 0.1524)
				(type default)
			)
			(layer "B.SilkS")
		)
		(fp_line
			(start -0.7874 0.4064)
			(end 0.7874 0.4064)
			(stroke
				(width 0.1524)
				(type default)
			)
			(layer "B.SilkS")
		)
		(fp_line
			(start 0.67945 -0.305054)
			(end 0.12065 -0.305054)
			(stroke
				(width 0.1)
				(type default)
			)
			(layer "B.Fab")
		)
		(fp_line
			(start 0.12065 -0.305054)
			(end 0.12065 -0.2794)
			(stroke
				(width 0.1)
				(type default)
			)
			(layer "B.Fab")
		)
		(fp_line
			(start -0.12065 -0.3048)
			(end -0.67945 -0.3048)
			(stroke
				(width 0.1)
				(type default)
			)
			(layer "B.Fab")
		)
		(fp_line
			(start -0.67945 -0.3048)
			(end -0.67945 0.3048)
			(stroke
				(width 0.1)
				(type default)
			)
			(layer "B.Fab")
		)
		(fp_line
			(start 0.12065 -0.2794)
			(end -0.12065 -0.2794)
			(stroke
				(width 0.1)
				(type default)
			)
			(layer "B.Fab")
		)
		(fp_line
			(start -0.12065 -0.2794)
			(end -0.12065 -0.3048)
			(stroke
				(width 0.1)
				(type default)
			)
			(layer "B.Fab")
		)
		(fp_line
			(start 0.12065 0.2794)
			(end 0.12065 0.3048)
			(stroke
				(width 0.1)
				(type default)
			)
			(layer "B.Fab")
		)
		(fp_line
			(start -0.120396 0.2794)
			(end 0.12065 0.2794)
			(stroke
				(width 0.1)
				(type default)
			)
			(layer "B.Fab")
		)
		(fp_line
			(start 0.67945 0.3048)
			(end 0.67945 -0.305054)
			(stroke
				(width 0.1)
				(type default)
			)
			(layer "B.Fab")
		)
		(fp_line
			(start 0.12065 0.3048)
			(end 0.67945 0.3048)
			(stroke
				(width 0.1)
				(type default)
			)
			(layer "B.Fab")
		)
		(fp_line
			(start -0.120396 0.3048)
			(end -0.120396 0.2794)
			(stroke
				(width 0.1)
				(type default)
			)
			(layer "B.Fab")
		)
		(fp_line
			(start -0.67945 0.3048)
			(end -0.120396 0.3048)
			(stroke
				(width 0.1)
				(type default)
			)
			(layer "B.Fab")
		)
		(pad "1" smd circle
			(at 0.40005 0 270)
			(size 0 0)
			(layers "B.Cu" "B.Mask" "B.Paste")
			(net "P2V5_AUX")
		)
		(pad "2" smd circle
			(at -0.40005 0 270)
			(size 0 0)
			(layers "B.Cu" "B.Mask" "B.Paste")
			(net "ADCVREFEXT0")
		)
	)
)
